(kicad_pcb
	(version 20260206)
	(generator "pcbnew")
	(generator_version "10.0")
	(general
		(thickness 1.6)
		(legacy_teardrops no)
	)
	(paper "A4")
	(title_block
		(title "01162023_DA0F0TEBIF0_F0T_Expander_BD_F_brd_V02_OCP.brd")
		(comment 1 "Grand Teton / footprints 4414-4419 of 9728")
	)
	(layers
		(0 "F.Cu" signal "TOP")
		(4 "In1.Cu" signal "GND")
		(6 "In2.Cu" signal "VCC")
		(8 "In3.Cu" signal "VCC1")
		(10 "In4.Cu" signal "GND1")
		(12 "In5.Cu" signal "IN1")
		(14 "In6.Cu" signal "GND2")
		(16 "In7.Cu" signal "IN2")
		(18 "In8.Cu" signal "GND3")
		(20 "In9.Cu" signal "IN3")
		(22 "In10.Cu" signal "GND4")
		(24 "In11.Cu" signal "IN4")
		(26 "In12.Cu" signal "GND5")
		(28 "In13.Cu" signal "IN5")
		(30 "In14.Cu" signal "GND6")
		(32 "In15.Cu" signal "IN6")
		(34 "In16.Cu" signal "GND7")
		(2 "B.Cu" signal "BOTTOM")
		(9 "F.Adhes" user "F.Adhesive")
		(11 "B.Adhes" user "B.Adhesive")
		(13 "F.Paste" user "Package Geometry/Pastemask Top")
		(15 "B.Paste" user "Package Geometry/Pastemask Bottom")
		(5 "F.SilkS" user "Ref Des/Silkscreen Top")
		(7 "B.SilkS" user "Ref Des/Silkscreen Bottom")
		(1 "F.Mask" user "Board Geometry/Soldermask Top")
		(3 "B.Mask" user "Board Geometry/Soldermask Bottom")
		(17 "Dwgs.User" user "User.Drawings")
		(19 "Cmts.User" user "User.Comments")
		(21 "Eco1.User" user "User.Eco1")
		(23 "Eco2.User" user "User.Eco2")
		(25 "Edge.Cuts" user "Board Geometry/Outline")
		(27 "Margin" user)
		(31 "F.CrtYd" user "Package Geometry/Place Bound Top")
		(29 "B.CrtYd" user "Package Geometry/Place Bound Bottom")
		(35 "F.Fab" user "Ref Des/Assembly Top")
		(33 "B.Fab" user "Ref Des/Assembly Bottom")
	)
	(footprint ""
		(layer "F.Cu")
		(at 108.260896 -392.778488)
		(property "Reference" "R6844"
			(at 0 0 0)
			(layer "F.SilkS")
			(hide yes)
			(effects
				(font
					(size 1.27 1.27)
				)
			)
		)
		(property "Value" ""
			(at 0 0 0)
			(layer "F.Fab")
			(effects
				(font
					(size 1.27 1.27)
				)
			)
		)
		(duplicate_pad_numbers_are_jumpers no)
		(fp_line
			(start -0.7874 -0.4064)
			(end 0.7874 -0.4064)
			(stroke
				(width 0.1524)
				(type default)
			)
			(layer "F.SilkS")
		)
		(fp_line
			(start -0.7874 0.4064)
			(end -0.7874 -0.4064)
			(stroke
				(width 0.1524)
				(type default)
			)
			(layer "F.SilkS")
		)
		(fp_line
			(start 0.7874 -0.4064)
			(end 0.7874 0.4064)
			(stroke
				(width 0.1524)
				(type default)
			)
			(layer "F.SilkS")
		)
		(fp_line
			(start 0.7874 0.4064)
			(end -0.7874 0.4064)
			(stroke
				(width 0.1524)
				(type default)
			)
			(layer "F.SilkS")
		)
		(fp_line
			(start -0.67945 -0.305054)
			(end -0.12065 -0.305054)
			(stroke
				(width 0.1)
				(type default)
			)
			(layer "F.Fab")
		)
		(fp_line
			(start -0.67945 0.3048)
			(end -0.67945 -0.305054)
			(stroke
				(width 0.1)
				(type default)
			)
			(layer "F.Fab")
		)
		(fp_line
			(start -0.12065 -0.305054)
			(end -0.12065 -0.2794)
			(stroke
				(width 0.1)
				(type default)
			)
			(layer "F.Fab")
		)
		(fp_line
			(start -0.12065 -0.2794)
			(end 0.12065 -0.2794)
			(stroke
				(width 0.1)
				(type default)
			)
			(layer "F.Fab")
		)
		(fp_line
			(start -0.12065 0.2794)
			(end -0.12065 0.3048)
			(stroke
				(width 0.1)
				(type default)
			)
			(layer "F.Fab")
		)
		(fp_line
			(start -0.12065 0.3048)
			(end -0.67945 0.3048)
			(stroke
				(width 0.1)
				(type default)
			)
			(layer "F.Fab")
		)
		(fp_line
			(start 0.120396 0.2794)
			(end -0.12065 0.2794)
			(stroke
				(width 0.1)
				(type default)
			)
			(layer "F.Fab")
		)
		(fp_line
			(start 0.120396 0.3048)
			(end 0.120396 0.2794)
			(stroke
				(width 0.1)
				(type default)
			)
			(layer "F.Fab")
		)
		(fp_line
			(start 0.12065 -0.3048)
			(end 0.67945 -0.3048)
			(stroke
				(width 0.1)
				(type default)
			)
			(layer "F.Fab")
		)
		(fp_line
			(start 0.12065 -0.2794)
			(end 0.12065 -0.3048)
			(stroke
				(width 0.1)
				(type default)
			)
			(layer "F.Fab")
		)
		(fp_line
			(start 0.67945 -0.3048)
			(end 0.67945 0.3048)
			(stroke
				(width 0.1)
				(type default)
			)
			(layer "F.Fab")
		)
		(fp_line
			(start 0.67945 0.3048)
			(end 0.120396 0.3048)
			(stroke
				(width 0.1)
				(type default)
			)
			(layer "F.Fab")
		)
		(pad "1" smd circle
			(at -0.40005 0)
			(size 0 0)
			(layers "F.Cu" "F.Mask" "F.Paste")
			(net "BIC_USB_HUB_XOUT")
		)
		(pad "2" smd circle
			(at 0.40005 0)
			(size 0 0)
			(layers "F.Cu" "F.Mask" "F.Paste")
			(net "BIC_USB_HUB_XOUT_R")
		)
	)
	(footprint ""
		(layer "F.Cu")
		(at 88.007444 -96.811592 -90)
		(property "Reference" "R696"
			(at 0 0 270)
			(layer "F.SilkS")
			(hide yes)
			(effects
				(font
					(size 1.27 1.27)
				)
			)
		)
		(property "Value" ""
			(at 0 0 270)
			(layer "F.Fab")
			(effects
				(font
					(size 1.27 1.27)
				)
			)
		)
		(duplicate_pad_numbers_are_jumpers no)
		(fp_line
			(start -0.7874 0.4064)
			(end -0.7874 -0.4064)
			(stroke
				(width 0.1524)
				(type default)
			)
			(layer "F.SilkS")
		)
		(fp_line
			(start 0.7874 0.4064)
			(end -0.7874 0.4064)
			(stroke
				(width 0.1524)
				(type default)
			)
			(layer "F.SilkS")
		)
		(fp_line
			(start -0.7874 -0.4064)
			(end 0.7874 -0.4064)
			(stroke
				(width 0.1524)
				(type default)
			)
			(layer "F.SilkS")
		)
		(fp_line
			(start 0.7874 -0.4064)
			(end 0.7874 0.4064)
			(stroke
				(width 0.1524)
				(type default)
			)
			(layer "F.SilkS")
		)
		(fp_line
			(start -0.67945 0.3048)
			(end -0.67945 -0.305054)
			(stroke
				(width 0.1)
				(type default)
			)
			(layer "F.Fab")
		)
		(fp_line
			(start -0.12065 0.3048)
			(end -0.67945 0.3048)
			(stroke
				(width 0.1)
				(type default)
			)
			(layer "F.Fab")
		)
		(fp_line
			(start 0.120396 0.3048)
			(end 0.120396 0.2794)
			(stroke
				(width 0.1)
				(type default)
			)
			(layer "F.Fab")
		)
		(fp_line
			(start 0.67945 0.3048)
			(end 0.120396 0.3048)
			(stroke
				(width 0.1)
				(type default)
			)
			(layer "F.Fab")
		)
		(fp_line
			(start -0.12065 0.2794)
			(end -0.12065 0.3048)
			(stroke
				(width 0.1)
				(type default)
			)
			(layer "F.Fab")
		)
		(fp_line
			(start 0.120396 0.2794)
			(end -0.12065 0.2794)
			(stroke
				(width 0.1)
				(type default)
			)
			(layer "F.Fab")
		)
		(fp_line
			(start -0.12065 -0.2794)
			(end 0.12065 -0.2794)
			(stroke
				(width 0.1)
				(type default)
			)
			(layer "F.Fab")
		)
		(fp_line
			(start 0.12065 -0.2794)
			(end 0.12065 -0.3048)
			(stroke
				(width 0.1)
				(type default)
			)
			(layer "F.Fab")
		)
		(fp_line
			(start 0.12065 -0.3048)
			(end 0.67945 -0.3048)
			(stroke
				(width 0.1)
				(type default)
			)
			(layer "F.Fab")
		)
		(fp_line
			(start 0.67945 -0.3048)
			(end 0.67945 0.3048)
			(stroke
				(width 0.1)
				(type default)
			)
			(layer "F.Fab")
		)
		(fp_line
			(start -0.67945 -0.305054)
			(end -0.12065 -0.305054)
			(stroke
				(width 0.1)
				(type default)
			)
			(layer "F.Fab")
		)
		(fp_line
			(start -0.12065 -0.305054)
			(end -0.12065 -0.2794)
			(stroke
				(width 0.1)
				(type default)
			)
			(layer "F.Fab")
		)
		(pad "1" smd circle
			(at -0.40005 0 270)
			(size 0 0)
			(layers "F.Cu" "F.Mask" "F.Paste")
			(net "NIC1_ADC_A1")
		)
		(pad "2" smd circle
			(at 0.40005 0 270)
			(size 0 0)
			(layers "F.Cu" "F.Mask" "F.Paste")
			(net "GND")
		)
	)
	(footprint ""
		(layer "F.Cu")
		(at 252.971046 -146.205956 180)
		(property "Reference" "C615"
			(at 0 0 180)
			(layer "F.SilkS")
			(hide yes)
			(effects
				(font
					(size 1.27 1.27)
				)
			)
		)
		(property "Value" ""
			(at 0 0 180)
			(layer "F.Fab")
			(effects
				(font
					(size 1.27 1.27)
				)
			)
		)
		(duplicate_pad_numbers_are_jumpers no)
		(fp_line
			(start 0.7874 0.4064)
			(end -0.7874 0.4064)
			(stroke
				(width 0.1524)
				(type default)
			)
			(layer "F.SilkS")
		)
		(fp_line
			(start 0.7874 -0.4064)
			(end 0.7874 0.4064)
			(stroke
				(width 0.1524)
				(type default)
			)
			(layer "F.SilkS")
		)
		(fp_line
			(start -0.7874 0.4064)
			(end -0.7874 -0.4064)
			(stroke
				(width 0.1524)
				(type default)
			)
			(layer "F.SilkS")
		)
		(fp_line
			(start -0.7874 -0.4064)
			(end 0.7874 -0.4064)
			(stroke
				(width 0.1524)
				(type default)
			)
			(layer "F.SilkS")
		)
		(fp_line
			(start 0.67945 0.3048)
			(end 0.120396 0.3048)
			(stroke
				(width 0.1)
				(type default)
			)
			(layer "F.Fab")
		)
		(fp_line
			(start 0.67945 -0.3048)
			(end 0.67945 0.3048)
			(stroke
				(width 0.1)
				(type default)
			)
			(layer "F.Fab")
		)
		(fp_line
			(start 0.12065 -0.2794)
			(end 0.12065 -0.3048)
			(stroke
				(width 0.1)
				(type default)
			)
			(layer "F.Fab")
		)
		(fp_line
			(start 0.12065 -0.3048)
			(end 0.67945 -0.3048)
			(stroke
				(width 0.1)
				(type default)
			)
			(layer "F.Fab")
		)
		(fp_line
			(start 0.120396 0.3048)
			(end 0.120396 0.2794)
			(stroke
				(width 0.1)
				(type default)
			)
			(layer "F.Fab")
		)
		(fp_line
			(start 0.120396 0.2794)
			(end -0.12065 0.2794)
			(stroke
				(width 0.1)
				(type default)
			)
			(layer "F.Fab")
		)
		(fp_line
			(start -0.12065 0.3048)
			(end -0.67945 0.3048)
			(stroke
				(width 0.1)
				(type default)
			)
			(layer "F.Fab")
		)
		(fp_line
			(start -0.12065 0.2794)
			(end -0.12065 0.3048)
			(stroke
				(width 0.1)
				(type default)
			)
			(layer "F.Fab")
		)
		(fp_line
			(start -0.12065 -0.2794)
			(end 0.12065 -0.2794)
			(stroke
				(width 0.1)
				(type default)
			)
			(layer "F.Fab")
		)
		(fp_line
			(start -0.12065 -0.305054)
			(end -0.12065 -0.2794)
			(stroke
				(width 0.1)
				(type default)
			)
			(layer "F.Fab")
		)
		(fp_line
			(start -0.67945 0.3048)
			(end -0.67945 -0.305054)
			(stroke
				(width 0.1)
				(type default)
			)
			(layer "F.Fab")
		)
		(fp_line
			(start -0.67945 -0.305054)
			(end -0.12065 -0.305054)
			(stroke
				(width 0.1)
				(type default)
			)
			(layer "F.Fab")
		)
		(pad "1" smd circle
			(at -0.40005 0 180)
			(size 0 0)
			(layers "F.Cu" "F.Mask" "F.Paste")
			(net "P12V_NIC4_VIN_P")
		)
		(pad "2" smd circle
			(at 0.40005 0 180)
			(size 0 0)
			(layers "F.Cu" "F.Mask" "F.Paste")
			(net "P12V_NIC4_VIN_N")
		)
	)
	(footprint ""
		(layer "F.Cu")
		(at 324.321678 -84.31149 180)
		(property "Reference" "U420"
			(at 1.284478 -2.32156 0)
			(unlocked yes)
			(layer "F.SilkS")
			(effects
				(font
					(size 0.7874 0.5842)
					(thickness 0.1524)
				)
				(justify left)
			)
		)
		(property "Value" ""
			(at 0 0 180)
			(layer "F.Fab")
			(effects
				(font
					(size 1.27 1.27)
				)
			)
		)
		(duplicate_pad_numbers_are_jumpers no)
		(fp_line
			(start 1.463548 1.549908)
			(end -1.463548 1.549908)
			(stroke
				(width 0.1524)
				(type default)
			)
			(layer "F.SilkS")
		)
		(fp_line
			(start 1.463548 -1.549908)
			(end 1.463548 1.549908)
			(stroke
				(width 0.1524)
				(type default)
			)
			(layer "F.SilkS")
		)
		(fp_line
			(start 0.762 -1.549908)
			(end 1.463548 -1.549908)
			(stroke
				(width 0.1524)
				(type default)
			)
			(layer "F.SilkS")
		)
		(fp_line
			(start 0 -0.762)
			(end 0.762 -1.549908)
			(stroke
				(width 0.1524)
				(type default)
			)
			(layer "F.SilkS")
		)
		(fp_line
			(start -0.787908 -1.549908)
			(end 0 -0.762)
			(stroke
				(width 0.1524)
				(type default)
			)
			(layer "F.SilkS")
		)
		(fp_line
			(start -1.463548 1.549908)
			(end -1.463548 -1.549908)
			(stroke
				(width 0.1524)
				(type default)
			)
			(layer "F.SilkS")
		)
		(fp_line
			(start -1.463548 -1.549908)
			(end -0.787908 -1.549908)
			(stroke
				(width 0.1524)
				(type default)
			)
			(layer "F.SilkS")
		)
		(fp_poly
			(pts
				(xy -3.4798 -1.359916) (xy -2.86004 -1.050036) (xy -3.4798 -0.740156)
			)
			(stroke
				(width 0)
				(type default)
			)
			(fill yes)
			(layer "F.SilkS")
		)
		(fp_line
			(start 1.549908 1.549908)
			(end -1.549908 1.549908)
			(stroke
				(width 0.1)
				(type default)
			)
			(layer "F.Fab")
		)
		(fp_line
			(start 1.549908 -1.549908)
			(end 1.549908 1.549908)
			(stroke
				(width 0.1)
				(type default)
			)
			(layer "F.Fab")
		)
		(fp_line
			(start -1.549908 1.549908)
			(end -1.549908 -1.549908)
			(stroke
				(width 0.1)
				(type default)
			)
			(layer "F.Fab")
		)
		(fp_line
			(start -1.549908 -1.549908)
			(end 1.549908 -1.549908)
			(stroke
				(width 0.1)
				(type default)
			)
			(layer "F.Fab")
		)
		(fp_poly
			(pts
				(xy -3.4798 -1.359916) (xy -2.86004 -1.050036) (xy -3.4798 -0.740156)
			)
			(stroke
				(width 0)
				(type default)
			)
			(fill yes)
			(layer "F.Fab")
		)
		(pad "1" smd rect
			(at -2.175002 -1.050036 270)
			(size 0.6096 1.1684)
			(layers "F.Cu" "F.Mask" "F.Paste")
			(net "P3V3")
		)
		(pad "2" smd rect
			(at -2.175002 -0.32512 270)
			(size 0.4318 1.1684)
			(layers "F.Cu" "F.Mask" "F.Paste")
			(net "SMB_ISO_CB_SCL")
		)
		(pad "3" smd rect
			(at -2.175002 0.32512 270)
			(size 0.4318 1.1684)
			(layers "F.Cu" "F.Mask" "F.Paste")
			(net "SMB_ISO_CB_SDA")
		)
		(pad "4" smd rect
			(at -2.175002 1.050036 270)
			(size 0.6096 1.1684)
			(layers "F.Cu" "F.Mask" "F.Paste")
			(net "GND")
		)
		(pad "5" smd rect
			(at 2.175002 1.050036 270)
			(size 0.6096 1.1684)
			(layers "F.Cu" "F.Mask" "F.Paste")
			(net "CB_ISO_EN")
		)
		(pad "6" smd rect
			(at 2.175002 0.32512 270)
			(size 0.4318 1.1684)
			(layers "F.Cu" "F.Mask" "F.Paste")
			(net "SMB_BIC_I2C6_MUX_FRU_R_SDA")
		)
		(pad "7" smd rect
			(at 2.175002 -0.32512 270)
			(size 0.4318 1.1684)
			(layers "F.Cu" "F.Mask" "F.Paste")
			(net "SMB_BIC_I2C6_MUX_FRU_R_SCL")
		)
		(pad "8" smd rect
			(at 2.175002 -1.050036 270)
			(size 0.6096 1.1684)
			(layers "F.Cu" "F.Mask" "F.Paste")
			(net "P3V3_AUX")
		)
	)
	(footprint ""
		(layer "F.Cu")
		(at 275.50999 -220.192854)
		(property "Reference" "ME10"
			(at 0.0762 -5.705348 0)
			(unlocked yes)
			(layer "F.SilkS")
			(effects
				(font
					(size 0.7874 0.5842)
					(thickness 0.1524)
				)
				(justify left)
			)
		)
		(property "Value" ""
			(at 0 0 0)
			(layer "F.Fab")
			(effects
				(font
					(size 1.27 1.27)
				)
			)
		)
		(duplicate_pad_numbers_are_jumpers no)
		(fp_line
			(start 0 -4.99999)
			(end 0 -3.47599)
			(stroke
				(width 0.1524)
				(type default)
			)
			(layer "F.SilkS")
		)
		(fp_line
			(start 0 -0.524002)
			(end 0 0.999998)
			(stroke
				(width 0.1524)
				(type default)
			)
			(layer "F.SilkS")
		)
		(fp_line
			(start 0 0.999998)
			(end 1.524 0.999998)
			(stroke
				(width 0.1524)
				(type default)
			)
			(layer "F.SilkS")
		)
		(fp_line
			(start 1.524 -4.99999)
			(end 0 -4.99999)
			(stroke
				(width 0.1524)
				(type default)
			)
			(layer "F.SilkS")
		)
		(fp_line
			(start 15.475966 0.999998)
			(end 16.999966 0.999998)
			(stroke
				(width 0.1524)
				(type default)
			)
			(layer "F.SilkS")
		)
		(fp_line
			(start 16.999966 -4.99999)
			(end 15.475966 -4.99999)
			(stroke
				(width 0.1524)
				(type default)
			)
			(layer "F.SilkS")
		)
		(fp_line
			(start 16.999966 -3.47599)
			(end 16.999966 -4.99999)
			(stroke
				(width 0.1524)
				(type default)
			)
			(layer "F.SilkS")
		)
		(fp_line
			(start 16.999966 0.999998)
			(end 16.999966 -0.524002)
			(stroke
				(width 0.1524)
				(type default)
			)
			(layer "F.SilkS")
		)
		(fp_text user "S/N"
			(at 0.1016 -3.54965 0)
			(unlocked yes)
			(layer "F.SilkS")
			(effects
				(font
					(size 1.905 1.4224)
					(thickness 0.1524)
				)
				(justify left)
			)
		)
	)
	(footprint ""
		(layer "F.Cu")
		(at 204.761592 -350.312482 90)
		(property "Reference" "R5799"
			(at 0 0 90)
			(layer "F.SilkS")
			(hide yes)
			(effects
				(font
					(size 1.27 1.27)
				)
			)
		)
		(property "Value" ""
			(at 0 0 90)
			(layer "F.Fab")
			(effects
				(font
					(size 1.27 1.27)
				)
			)
		)
		(duplicate_pad_numbers_are_jumpers no)
		(fp_line
			(start 0.7874 -0.4064)
			(end 0.7874 0.4064)
			(stroke
				(width 0.1524)
				(type default)
			)
			(layer "F.SilkS")
		)
		(fp_line
			(start -0.7874 -0.4064)
			(end 0.7874 -0.4064)
			(stroke
				(width 0.1524)
				(type default)
			)
			(layer "F.SilkS")
		)
		(fp_line
			(start 0.7874 0.4064)
			(end -0.7874 0.4064)
			(stroke
				(width 0.1524)
				(type default)
			)
			(layer "F.SilkS")
		)
		(fp_line
			(start -0.7874 0.4064)
			(end -0.7874 -0.4064)
			(stroke
				(width 0.1524)
				(type default)
			)
			(layer "F.SilkS")
		)
		(fp_line
			(start -0.12065 -0.305054)
			(end -0.12065 -0.2794)
			(stroke
				(width 0.1)
				(type default)
			)
			(layer "F.Fab")
		)
		(fp_line
			(start -0.67945 -0.305054)
			(end -0.12065 -0.305054)
			(stroke
				(width 0.1)
				(type default)
			)
			(layer "F.Fab")
		)
		(fp_line
			(start 0.67945 -0.3048)
			(end 0.67945 0.3048)
			(stroke
				(width 0.1)
				(type default)
			)
			(layer "F.Fab")
		)
		(fp_line
			(start 0.12065 -0.3048)
			(end 0.67945 -0.3048)
			(stroke
				(width 0.1)
				(type default)
			)
			(layer "F.Fab")
		)
		(fp_line
			(start 0.12065 -0.2794)
			(end 0.12065 -0.3048)
			(stroke
				(width 0.1)
				(type default)
			)
			(layer "F.Fab")
		)
		(fp_line
			(start -0.12065 -0.2794)
			(end 0.12065 -0.2794)
			(stroke
				(width 0.1)
				(type default)
			)
			(layer "F.Fab")
		)
		(fp_line
			(start 0.120396 0.2794)
			(end -0.12065 0.2794)
			(stroke
				(width 0.1)
				(type default)
			)
			(layer "F.Fab")
		)
		(fp_line
			(start -0.12065 0.2794)
			(end -0.12065 0.3048)
			(stroke
				(width 0.1)
				(type default)
			)
			(layer "F.Fab")
		)
		(fp_line
			(start 0.67945 0.3048)
			(end 0.120396 0.3048)
			(stroke
				(width 0.1)
				(type default)
			)
			(layer "F.Fab")
		)
		(fp_line
			(start 0.120396 0.3048)
			(end 0.120396 0.2794)
			(stroke
				(width 0.1)
				(type default)
			)
			(layer "F.Fab")
		)
		(fp_line
			(start -0.12065 0.3048)
			(end -0.67945 0.3048)
			(stroke
				(width 0.1)
				(type default)
			)
			(layer "F.Fab")
		)
		(fp_line
			(start -0.67945 0.3048)
			(end -0.67945 -0.305054)
			(stroke
				(width 0.1)
				(type default)
			)
			(layer "F.Fab")
		)
		(pad "1" smd circle
			(at -0.40005 0 90)
			(size 0 0)
			(layers "F.Cu" "F.Mask" "F.Paste")
			(net "HSC_D_OC_BUF_R_N")
		)
		(pad "2" smd circle
			(at 0.40005 0 90)
			(size 0 0)
			(layers "F.Cu" "F.Mask" "F.Paste")
			(net "HSC_D_OC_BUF_N")
		)
	)
)
